# S9S_MB_2U (Grand Teton) — schematic netlist excerpt (pin names and nets, part order shuffled) for the footprints in the layout excerpt that follows; sources: Cadence DE-HDL packaged netlist, KiCad conversion of 03242023_DA0F0TMBIJ0_F0T_Motherboard_J_brd_V01_OCP.brd

J20  SCONN288_ADR50017P087CC  SCONN288_ADR50017-P087CC IO  pkg DDR288S_1-1VXB  page 101
  VIN_BULK0  = P12V_S3_AUX_CPU1_NVDIMM
  RFU0  = TP_CHB_CPU1_DIMM2_FRU_0
  VIN_MGMT  = P3V3_AUX
  HSCL  = I3C_SPD_DDRABCD_CPU1_LVC1_SCL_3
  HSDA  = I3C_SPD_DDRABCD_CPU1_LVC1_SDA
  VSS0  = GND
  DQ0_A  = M_B_CPU1_SA_DQ<0>
  VSS1  = GND
  DQ1_A  = M_B_CPU1_SA_DQ<1>
  VSS2  = GND
  DQS0_A_T  = M_B_CPU1_SA_DQS_DP<0>
  DQS0_A_C  = M_B_CPU1_SA_DQS_DN<0>
  VSS3  = GND
  DQ4_A  = M_B_CPU1_SA_DQ<4>
  VSS4  = GND
  DQ5_A  = M_B_CPU1_SA_DQ<5>
  VSS5  = GND
  DQ8_A  = M_B_CPU1_SA_DQ<8>
  VSS6  = GND
  DQ9_A  = M_B_CPU1_SA_DQ<9>
  VSS7  = GND
  DQS1_A_T  = M_B_CPU1_SA_DQS_DP<1>
  DQS1_A_C  = M_B_CPU1_SA_DQS_DN<1>
  VSS8  = GND
  DQ12_A  = M_B_CPU1_SA_DQ<12>
  VSS9  = GND
  DQ13_A  = M_B_CPU1_SA_DQ<13>
  VSS10  = GND
  DQ16_A  = M_B_CPU1_SA_DQ<16>
  VSS11  = GND
  DQ17_A  = M_B_CPU1_SA_DQ<17>
  VSS12  = GND
  DQS2_A_T  = M_B_CPU1_SA_DQS_DP<2>
  DQS2_A_C  = M_B_CPU1_SA_DQS_DN<2>
  VSS13  = GND
  DQ20_A  = M_B_CPU1_SA_DQ<20>
  VSS14  = GND
  DQ21_A  = M_B_CPU1_SA_DQ<21>
  VSS15  = GND
  DQ24_A  = M_B_CPU1_SA_DQ<24>
  VSS16  = GND
  DQ25_A  = M_B_CPU1_SA_DQ<25>
  VSS17  = GND
  DQS3_A_T  = M_B_CPU1_SA_DQS_DP<3>
  DQS3_A_C  = M_B_CPU1_SA_DQS_DN<3>
  VSS18  = GND
  DQ28_A  = M_B_CPU1_SA_DQ<28>
  VSS19  = GND
  DQ29_A  = M_B_CPU1_SA_DQ<29>
  VSS20  = GND
  CB0_A  = M_B_CPU1_SA_CB<0>
  VSS21  = GND
  CB1_A  = M_B_CPU1_SA_CB<1>
  VSS22  = GND
  DQS4_A_T  = M_B_CPU1_SA_DQS_DP<4>
  DQS4_A_C  = M_B_CPU1_SA_DQS_DN<4>
  VSS23  = GND
  CB4_A  = M_B_CPU1_SA_CB<4>
  VSS24  = GND
  CB5_A  = M_B_CPU1_SA_CB<5>
  VSS25  = GND
  ALERT_N  = M_B_CPU1_ALERT_N
  VSS26  = GND
  CS0_A_N  = M_B_CPU1_SA_CS_N<2>
  VSS27  = GND
  CA0_A  = M_B_CPU1_SA_CA<0>
  VSS28  = GND
  CA2_A  = M_B_CPU1_SA_CA<2>
  VSS29  = GND
  CA4_A  = M_B_CPU1_SA_CA<4>
  VSS30  = GND
  CA6_A  = M_B_CPU1_SA_CA<6>
  VSS31  = GND
  PAR_A  = M_B_CPU1_SA_PAR
  VSS32  = GND
  CA0_B  = M_B_CPU1_SB_CA<0>
  VSS33  = GND
  CA2_B  = M_B_CPU1_SB_CA<2>
  VSS34  = GND
  CA4_B  = M_B_CPU1_SB_CA<4>
  VSS35  = GND
  CA6_B  = M_B_CPU1_SB_CA<6>
  VSS36  = GND
  CS0_B_N  = M_B_CPU1_SB_CS_N<2>
  VSS37  = GND
  \lbd||rsp_a_n\  = M_B_CPU1_SA_RSP<1>
  \lbs||rsp_b_n\  = M_B_CPU1_SB_RSP<1>
  VSS38  = GND
  CB4_B  = M_B_CPU1_SB_CB<4>
  VSS39  = GND
  CB5_B  = M_B_CPU1_SB_CB<5>
  VSS40  = GND
  \dqs9_b_t||tdqs9_b_t||dbi4_b_n\  = M_B_CPU1_SB_DQS_DP<9>
  \dqs9_b_c||tdqs9_b_c\  = M_B_CPU1_SB_DQS_DN<9>
  VSS41  = GND
  CB0_B  = M_B_CPU1_SB_CB<0>
  VSS42  = GND
  CB1_B  = M_B_CPU1_SB_CB<1>
  VSS43  = GND
  DQ0_B  = M_B_CPU1_SB_DQ<0>
  VSS44  = GND
  DQ1_B  = M_B_CPU1_SB_DQ<1>
  VSS45  = GND
  DQS0_B_T  = M_B_CPU1_SB_DQS_DP<0>
  DQS0_B_C  = M_B_CPU1_SB_DQS_DN<0>
  VSS46  = GND
  DQ4_B  = M_B_CPU1_SB_DQ<4>
  VSS47  = GND
  DQ5_B  = M_B_CPU1_SB_DQ<5>
  VSS48  = GND
  DQ8_B  = M_B_CPU1_SB_DQ<8>
  VSS49  = GND
  DQ9_B  = M_B_CPU1_SB_DQ<9>
  VSS50  = GND
  DQS1_B_T  = M_B_CPU1_SB_DQS_DP<1>
  DQS1_B_C  = M_B_CPU1_SB_DQS_DN<1>
  VSS51  = GND
  DQ12_B  = M_B_CPU1_SB_DQ<12>
  VSS52  = GND
  DQ13_B  = M_B_CPU1_SB_DQ<13>
  VSS53  = GND
  DQ16_B  = M_B_CPU1_SB_DQ<16>
  VSS54  = GND
  DQ17_B  = M_B_CPU1_SB_DQ<17>
  VSS55  = GND
  DQS2_B_T  = M_B_CPU1_SB_DQS_DP<2>
  DQS2_B_C  = M_B_CPU1_SB_DQS_DN<2>
  VSS56  = GND
  DQ20_B  = M_B_CPU1_SB_DQ<20>
  VSS57  = GND
  DQ21_B  = M_B_CPU1_SB_DQ<21>
  VSS58  = GND
  DQ24_B  = M_B_CPU1_SB_DQ<24>
  VSS59  = GND
  DQ25_B  = M_B_CPU1_SB_DQ<25>
  VSS60  = GND
  DQS3_B_T  = M_B_CPU1_SB_DQS_DP<3>
  DQS3_B_C  = M_B_CPU1_SB_DQS_DN<3>
  VSS61  = GND
  DQ28_B  = M_B_CPU1_SB_DQ<28>
  VSS62  = GND
  DQ29_B  = M_B_CPU1_SB_DQ<29>
  VSS63  = GND
  RFU1  = TP_CHB_CPU1_DIMM2_FRU_1
  VIN_BULK1  = P12V_S3_AUX_CPU1_NVDIMM
  VIN_BULK2  = P12V_S3_AUX_CPU1_NVDIMM
  \pwr_good||fail_n\  = PWRGD_CHB_CPU1_DIMM2
  HSA  = PD_CHB_CPU1_DIMM2_SAA
  RFU2  = TP_CHB_CPU1_DIMM2_FRU_2
  RFU3  = TP_CHB_CPU1_DIMM2_FRU_3
  VSS64  = GND
  DQ2_A  = M_B_CPU1_SA_DQ<2>
  VSS65  = GND
  DQ3_A  = M_B_CPU1_SA_DQ<3>
  VSS66  = GND
  \dqs5_a_c||tdqs5_a_c||dqs5_a_t||tdqs5_a_t\  = M_B_CPU1_SA_DQS_DN<5>
  \dqs5_a_t||tdqs5_a_t\  = M_B_CPU1_SA_DQS_DP<5>
  VSS67  = GND
  DQ6_A  = M_B_CPU1_SA_DQ<6>
  VSS68  = GND
  DQ7_A  = M_B_CPU1_SA_DQ<7>
  VSS69  = GND
  DQ10_A  = M_B_CPU1_SA_DQ<10>
  VSS70  = GND
  DQ11_A  = M_B_CPU1_SA_DQ<11>
  VSS71  = GND
  \dqs6_a_c||tdqs6_a_c||dqs6_a_t||tdqs6_a_t\  = M_B_CPU1_SA_DQS_DN<6>
  \dqs6_a_t||tdqs6_a_t\  = M_B_CPU1_SA_DQS_DP<6>
  VSS72  = GND
  DQ14_A  = M_B_CPU1_SA_DQ<14>
  VSS73  = GND
  DQ15_A  = M_B_CPU1_SA_DQ<15>
  VSS74  = GND
  DQ18_A  = M_B_CPU1_SA_DQ<18>
  VSS75  = GND
  DQ19_A  = M_B_CPU1_SA_DQ<19>
  VSS76  = GND
  \dqs7_a_c||tdqs7_a_c\  = M_B_CPU1_SA_DQS_DN<7>
  \dqs7_a_t||tdqs7_a_t\  = M_B_CPU1_SA_DQS_DP<7>
  VSS77  = GND
  DQ22_A  = M_B_CPU1_SA_DQ<22>
  VSS78  = GND
  DQ23_A  = M_B_CPU1_SA_DQ<23>
  VSS79  = GND
  DQ26_A  = M_B_CPU1_SA_DQ<26>
  VSS80  = GND
  DQ27_A  = M_B_CPU1_SA_DQ<27>
  VSS81  = GND
  \dqs8_a_c||tdqs8_a_c\  = M_B_CPU1_SA_DQS_DN<8>
  \dqs8_a_t||tdqs8_a_t\  = M_B_CPU1_SA_DQS_DP<8>
  VSS82  = GND
  DQ30_A  = M_B_CPU1_SA_DQ<30>
  VSS83  = GND
  DQ31_A  = M_B_CPU1_SA_DQ<31>
  VSS84  = GND
  CB2_A  = M_B_CPU1_SA_CB<2>
  VSS85  = GND
  CB3_A  = M_B_CPU1_SA_CB<3>
  VSS86  = GND
  \dqs9_a_c||tdqs9_a_c\  = M_B_CPU1_SA_DQS_DN<9>
  \dqs9_a_t||tdqs9_a_t\  = M_B_CPU1_SA_DQS_DP<9>
  VSS87  = GND
  CB6_A  = M_B_CPU1_SA_CB<6>
  VSS88  = GND
  CB7_A  = M_B_CPU1_SA_CB<7>
  VSS89  = GND
  RESET_N  = RST_M_AB_CPU1_FPGA_N
  VSS90  = GND
  CS1_A_N  = M_B_CPU1_SA_CS_N<3>
  VSS91  = GND
  CA1_A  = M_B_CPU1_SA_CA<1>
  VSS92  = GND
  CA3_A  = M_B_CPU1_SA_CA<3>
  VSS93  = GND
  CA5_A  = M_B_CPU1_SA_CA<5>
  VSS94  = GND
  CK_T  = M_B_CPU1_CLK_DP<1>
  CK_C  = M_B_CPU1_CLK_DN<1>
  VSS95  = GND
  RFU4  = TP_CHB_CPU1_DIMM2_FRU_4
  CA1_B  = M_B_CPU1_SB_CA<1>
  VSS96  = GND
  CA3_B  = M_B_CPU1_SB_CA<3>
  VSS97  = GND
  CA5_B  = M_B_CPU1_SB_CA<5>
  VSS98  = GND
  PAR_B  = M_B_CPU1_SB_PAR
  VSS99  = GND
  CS1_B_N  = M_B_CPU1_SB_CS_N<3>
  VSS100  = GND
  RFU5  = TP_CHB_CPU1_DIMM2_FRU_5
  RFU6  = TP_CHB_CPU1_DIMM2_FRU_6
  VSS101  = GND
  CB6_B  = M_B_CPU1_SB_CB<6>
  VSS102  = GND
  CB7_B  = M_B_CPU1_SB_CB<7>
  VSS103  = GND
  DQS4_B_C  = M_B_CPU1_SB_DQS_DN<4>
  DQS4_B_T  = M_B_CPU1_SB_DQS_DP<4>
  VSS104  = GND
  CB2_B  = M_B_CPU1_SB_CB<2>
  VSS105  = GND
  CB3_B  = M_B_CPU1_SB_CB<3>
  VSS106  = GND
  DQ2_B  = M_B_CPU1_SB_DQ<2>
  VSS107  = GND
  DQ3_B  = M_B_CPU1_SB_DQ<3>
  VSS108  = GND
  \dqs5_b_c||tdqs5_b_c\  = M_B_CPU1_SB_DQS_DN<5>
  \dqs5_b_t||tdqs5_b_t\  = M_B_CPU1_SB_DQS_DP<5>
  VSS109  = GND
  DQ6_B  = M_B_CPU1_SB_DQ<6>
  VSS110  = GND
  DQ7_B  = M_B_CPU1_SB_DQ<7>
  VSS111  = GND
  DQ10_B  = M_B_CPU1_SB_DQ<10>
  VSS112  = GND
  DQ11_B  = M_B_CPU1_SB_DQ<11>
  VSS113  = GND
  \dqs6_b_c||tdqs6_b_c\  = M_B_CPU1_SB_DQS_DN<6>
  \dqs6_b_t||tdqs6_b_t\  = M_B_CPU1_SB_DQS_DP<6>
  VSS114  = GND
  DQ14_B  = M_B_CPU1_SB_DQ<14>
  VSS115  = GND
  DQ15_B  = M_B_CPU1_SB_DQ<15>
  VSS116  = GND
  DQ18_B  = M_B_CPU1_SB_DQ<18>
  VSS117  = GND
  DQ19_B  = M_B_CPU1_SB_DQ<19>
  VSS118  = GND
  \dqs7_b_c||tdqs7_b_c\  = M_B_CPU1_SB_DQS_DN<7>
  \dqs7_b_t||tdqs7_b_t\  = M_B_CPU1_SB_DQS_DP<7>
  VSS119  = GND
  DQ22_B  = M_B_CPU1_SB_DQ<22>
  VSS120  = GND
  DQ23_B  = M_B_CPU1_SB_DQ<23>
  VSS121  = GND
  DQ26_B  = M_B_CPU1_SB_DQ<26>
  VSS122  = GND
  DQ27_B  = M_B_CPU1_SB_DQ<27>
  VSS123  = GND
  \dqs8_b_c||tdqs8_b_c\  = M_B_CPU1_SB_DQS_DN<8>
  \dqs8_b_t||tdqs8_b_t\  = M_B_CPU1_SB_DQS_DP<8>
  VSS124  = GND
  DQ30_B  = M_B_CPU1_SB_DQ<30>
  VSS125  = GND
  DQ31_B  = M_B_CPU1_SB_DQ<31>
  VSS126  = GND
  G1  = GND
  G2  = GND
  G3  = GND

(kicad_pcb
	(version 20260206)
	(generator "pcbnew")
	(generator_version "10.0")
	(general
		(thickness 1.6)
		(legacy_teardrops no)
	)
	(paper "A4")
	(title_block
		(title "03242023_DA0F0TMBIJ0_F0T_Motherboard_J_brd_V01_OCP.brd")
		(comment 1 "Grand Teton / footprint 1508 of 6105 (J20), pads 138-182 of 291")
	)
	(layers
		(0 "F.Cu" signal "TOP")
		(4 "In1.Cu" signal "GND")
		(6 "In2.Cu" signal "IN1")
		(8 "In3.Cu" signal "GND1")
		(10 "In4.Cu" signal "IN2")
		(12 "In5.Cu" signal "GND2")
		(14 "In6.Cu" signal "IN3")
		(16 "In7.Cu" signal "GND3")
		(18 "In8.Cu" signal "VCC")
		(20 "In9.Cu" signal "VCC1")
		(22 "In10.Cu" signal "GND4")
		(24 "In11.Cu" signal "IN4")
		(26 "In12.Cu" signal "GND5")
		(28 "In13.Cu" signal "IN5")
		(30 "In14.Cu" signal "GND6")
		(32 "In15.Cu" signal "IN6")
		(34 "In16.Cu" signal "GND7")
		(2 "B.Cu" signal "BOTTOM")
		(9 "F.Adhes" user "F.Adhesive")
		(11 "B.Adhes" user "B.Adhesive")
		(13 "F.Paste" user "Package Geometry/Pastemask Top")
		(15 "B.Paste" user "Package Geometry/Pastemask Bottom")
		(5 "F.SilkS" user "Ref Des/Silkscreen Top")
		(7 "B.SilkS" user "Ref Des/Silkscreen Bottom")
		(1 "F.Mask" user "Board Geometry/Soldermask Top")
		(3 "B.Mask" user "Board Geometry/Soldermask Bottom")
		(17 "Dwgs.User" user "User.Drawings")
		(19 "Cmts.User" user "User.Comments")
		(21 "Eco1.User" user "User.Eco1")
		(23 "Eco2.User" user "User.Eco2")
		(25 "Edge.Cuts" user "Board Geometry/Outline")
		(27 "Margin" user)
		(31 "F.CrtYd" user "Package Geometry/Place Bound Top")
		(29 "B.CrtYd" user "Package Geometry/Place Bound Bottom")
		(35 "F.Fab" user "Ref Des/Assembly Top")
		(33 "B.Fab" user "Ref Des/Assembly Bottom")
	)
	(footprint ""
		(layer "F.Cu")
		(at 47.90948 -258.091686)
		(property "Reference" "J20"
			(at -2.74066 -81.678272 0)
			(unlocked yes)
			(layer "F.SilkS")
			(effects
				(font
					(size 0.7874 0.5842)
					(thickness 0.1524)
				)
				(justify left)
			)
		)
		(property "Value" ""
			(at 0 0 0)
			(layer "F.Fab")
			(effects
				(font
					(size 1.27 1.27)
				)
			)
		)
		(duplicate_pad_numbers_are_jumpers no)
		(pad "138" smd rect
			(at -2.050034 58.224928 270)
			(size 0.519938 1.4986)
			(layers "F.Cu" "F.Mask" "F.Paste")
			(net "M_B_CPU1_SB_DQS_DN<3>")
		)
		(pad "139" smd rect
			(at -2.050034 59.075066 270)
			(size 0.519938 1.4986)
			(layers "F.Cu" "F.Mask" "F.Paste")
			(net "GND")
		)
		(pad "140" smd rect
			(at -2.050034 59.92495 270)
			(size 0.519938 1.4986)
			(layers "F.Cu" "F.Mask" "F.Paste")
			(net "M_B_CPU1_SB_DQ<28>")
		)
		(pad "141" smd rect
			(at -2.050034 60.775088 270)
			(size 0.519938 1.4986)
			(layers "F.Cu" "F.Mask" "F.Paste")
			(net "GND")
		)
		(pad "142" smd rect
			(at -2.050034 61.624972 270)
			(size 0.519938 1.4986)
			(layers "F.Cu" "F.Mask" "F.Paste")
			(net "M_B_CPU1_SB_DQ<29>")
		)
		(pad "143" smd rect
			(at -2.050034 62.47511 270)
			(size 0.519938 1.4986)
			(layers "F.Cu" "F.Mask" "F.Paste")
			(net "GND")
		)
		(pad "144" smd rect
			(at -2.050034 63.324994 270)
			(size 0.519938 1.4986)
			(layers "F.Cu" "F.Mask" "F.Paste")
			(net "TP_CHB_CPU1_DIMM2_FRU_1")
		)
		(pad "145" smd rect
			(at 2.050034 -63.324994 270)
			(size 0.519938 1.4986)
			(layers "F.Cu" "F.Mask" "F.Paste")
			(net "P12V_S3_AUX_CPU1_NVDIMM")
		)
		(pad "146" smd rect
			(at 2.050034 -62.47511 270)
			(size 0.519938 1.4986)
			(layers "F.Cu" "F.Mask" "F.Paste")
			(net "P12V_S3_AUX_CPU1_NVDIMM")
		)
		(pad "147" smd rect
			(at 2.050034 -61.624972 270)
			(size 0.519938 1.4986)
			(layers "F.Cu" "F.Mask" "F.Paste")
			(net "PWRGD_CHB_CPU1_DIMM2")
		)
		(pad "148" smd rect
			(at 2.050034 -60.775088 270)
			(size 0.519938 1.4986)
			(layers "F.Cu" "F.Mask" "F.Paste")
			(net "PD_CHB_CPU1_DIMM2_SAA")
		)
		(pad "149" smd rect
			(at 2.050034 -59.92495 270)
			(size 0.519938 1.4986)
			(layers "F.Cu" "F.Mask" "F.Paste")
			(net "TP_CHB_CPU1_DIMM2_FRU_2")
		)
		(pad "150" smd rect
			(at 2.050034 -59.075066 270)
			(size 0.519938 1.4986)
			(layers "F.Cu" "F.Mask" "F.Paste")
			(net "TP_CHB_CPU1_DIMM2_FRU_3")
		)
		(pad "151" smd rect
			(at 2.050034 -58.224928 270)
			(size 0.519938 1.4986)
			(layers "F.Cu" "F.Mask" "F.Paste")
			(net "GND")
		)
		(pad "152" smd rect
			(at 2.050034 -57.375044 270)
			(size 0.519938 1.4986)
			(layers "F.Cu" "F.Mask" "F.Paste")
			(net "M_B_CPU1_SA_DQ<2>")
		)
		(pad "153" smd rect
			(at 2.050034 -56.524906 270)
			(size 0.519938 1.4986)
			(layers "F.Cu" "F.Mask" "F.Paste")
			(net "GND")
		)
		(pad "154" smd rect
			(at 2.050034 -55.675022 270)
			(size 0.519938 1.4986)
			(layers "F.Cu" "F.Mask" "F.Paste")
			(net "M_B_CPU1_SA_DQ<3>")
		)
		(pad "155" smd rect
			(at 2.050034 -54.824884 270)
			(size 0.519938 1.4986)
			(layers "F.Cu" "F.Mask" "F.Paste")
			(net "GND")
		)
		(pad "156" smd rect
			(at 2.050034 -53.975 270)
			(size 0.519938 1.4986)
			(layers "F.Cu" "F.Mask" "F.Paste")
			(net "M_B_CPU1_SA_DQS_DN<5>")
		)
		(pad "157" smd rect
			(at 2.050034 -53.125116 270)
			(size 0.519938 1.4986)
			(layers "F.Cu" "F.Mask" "F.Paste")
			(net "M_B_CPU1_SA_DQS_DP<5>")
		)
		(pad "158" smd rect
			(at 2.050034 -52.274978 270)
			(size 0.519938 1.4986)
			(layers "F.Cu" "F.Mask" "F.Paste")
			(net "GND")
		)
		(pad "159" smd rect
			(at 2.050034 -51.425094 270)
			(size 0.519938 1.4986)
			(layers "F.Cu" "F.Mask" "F.Paste")
			(net "M_B_CPU1_SA_DQ<6>")
		)
		(pad "160" smd rect
			(at 2.050034 -50.574956 270)
			(size 0.519938 1.4986)
			(layers "F.Cu" "F.Mask" "F.Paste")
			(net "GND")
		)
		(pad "161" smd rect
			(at 2.050034 -49.725072 270)
			(size 0.519938 1.4986)
			(layers "F.Cu" "F.Mask" "F.Paste")
			(net "M_B_CPU1_SA_DQ<7>")
		)
		(pad "162" smd rect
			(at 2.050034 -48.874934 270)
			(size 0.519938 1.4986)
			(layers "F.Cu" "F.Mask" "F.Paste")
			(net "GND")
		)
		(pad "163" smd rect
			(at 2.050034 -48.02505 270)
			(size 0.519938 1.4986)
			(layers "F.Cu" "F.Mask" "F.Paste")
			(net "M_B_CPU1_SA_DQ<10>")
		)
		(pad "164" smd rect
			(at 2.050034 -47.174912 270)
			(size 0.519938 1.4986)
			(layers "F.Cu" "F.Mask" "F.Paste")
			(net "GND")
		)
		(pad "165" smd rect
			(at 2.050034 -46.325028 270)
			(size 0.519938 1.4986)
			(layers "F.Cu" "F.Mask" "F.Paste")
			(net "M_B_CPU1_SA_DQ<11>")
		)
		(pad "166" smd rect
			(at 2.050034 -45.47489 270)
			(size 0.519938 1.4986)
			(layers "F.Cu" "F.Mask" "F.Paste")
			(net "GND")
		)
		(pad "167" smd rect
			(at 2.050034 -44.625006 270)
			(size 0.519938 1.4986)
			(layers "F.Cu" "F.Mask" "F.Paste")
			(net "M_B_CPU1_SA_DQS_DN<6>")
		)
		(pad "168" smd rect
			(at 2.050034 -43.775122 270)
			(size 0.519938 1.4986)
			(layers "F.Cu" "F.Mask" "F.Paste")
			(net "M_B_CPU1_SA_DQS_DP<6>")
		)
		(pad "169" smd rect
			(at 2.050034 -42.924984 270)
			(size 0.519938 1.4986)
			(layers "F.Cu" "F.Mask" "F.Paste")
			(net "GND")
		)
		(pad "170" smd rect
			(at 2.050034 -42.0751 270)
			(size 0.519938 1.4986)
			(layers "F.Cu" "F.Mask" "F.Paste")
			(net "M_B_CPU1_SA_DQ<14>")
		)
		(pad "171" smd rect
			(at 2.050034 -41.224962 270)
			(size 0.519938 1.4986)
			(layers "F.Cu" "F.Mask" "F.Paste")
			(net "GND")
		)
		(pad "172" smd rect
			(at 2.050034 -40.375078 270)
			(size 0.519938 1.4986)
			(layers "F.Cu" "F.Mask" "F.Paste")
			(net "M_B_CPU1_SA_DQ<15>")
		)
		(pad "173" smd rect
			(at 2.050034 -39.52494 270)
			(size 0.519938 1.4986)
			(layers "F.Cu" "F.Mask" "F.Paste")
			(net "GND")
		)
		(pad "174" smd rect
			(at 2.050034 -38.675056 270)
			(size 0.519938 1.4986)
			(layers "F.Cu" "F.Mask" "F.Paste")
			(net "M_B_CPU1_SA_DQ<18>")
		)
		(pad "175" smd rect
			(at 2.050034 -37.824918 270)
			(size 0.519938 1.4986)
			(layers "F.Cu" "F.Mask" "F.Paste")
			(net "GND")
		)
		(pad "176" smd rect
			(at 2.050034 -36.975034 270)
			(size 0.519938 1.4986)
			(layers "F.Cu" "F.Mask" "F.Paste")
			(net "M_B_CPU1_SA_DQ<19>")
		)
		(pad "177" smd rect
			(at 2.050034 -36.124896 270)
			(size 0.519938 1.4986)
			(layers "F.Cu" "F.Mask" "F.Paste")
			(net "GND")
		)
		(pad "178" smd rect
			(at 2.050034 -35.275012 270)
			(size 0.519938 1.4986)
			(layers "F.Cu" "F.Mask" "F.Paste")
			(net "M_B_CPU1_SA_DQS_DN<7>")
		)
		(pad "179" smd rect
			(at 2.050034 -34.425128 270)
			(size 0.519938 1.4986)
			(layers "F.Cu" "F.Mask" "F.Paste")
			(net "M_B_CPU1_SA_DQS_DP<7>")
		)
		(pad "180" smd rect
			(at 2.050034 -33.57499 270)
			(size 0.519938 1.4986)
			(layers "F.Cu" "F.Mask" "F.Paste")
			(net "GND")
		)
		(pad "181" smd rect
			(at 2.050034 -32.725106 270)
			(size 0.519938 1.4986)
			(layers "F.Cu" "F.Mask" "F.Paste")
			(net "M_B_CPU1_SA_DQ<22>")
		)
		(pad "182" smd rect
			(at 2.050034 -31.874968 270)
			(size 0.519938 1.4986)
			(layers "F.Cu" "F.Mask" "F.Paste")
			(net "GND")
		)
	)
)
